# S9S_MB_2U (Grand Teton) — schematic netlist excerpt (pin names and nets, part order shuffled) for the footprints in the layout excerpt that follows; sources: Cadence DE-HDL packaged netlist, KiCad conversion of 03242023_DA0F0TMBIJ0_F0T_Motherboard_J_brd_V01_OCP.brd

J73  PICOPROBE_BXA  DELTA-L 4.0 EMPTY  pkg TRIANG_LAUNCH_3PXB  page 308
  \1_p\  = DELTA_L_85_5INCH_IN3_DN
  \2_n\  = DELTA_L_85_5INCH_IN3_DP
  \3_g\  = DELTA_L_GND_1

(kicad_pcb
	(version 20260206)
	(generator "pcbnew")
	(generator_version "10.0")
	(general
		(thickness 1.6)
		(legacy_teardrops no)
	)
	(paper "A4")
	(title_block
		(title "03242023_DA0F0TMBIJ0_F0T_Motherboard_J_brd_V01_OCP.brd")
		(comment 1 "Grand Teton / footprints 2190-2190 of 6105")
	)
	(layers
		(0 "F.Cu" signal "TOP")
		(4 "In1.Cu" signal "GND")
		(6 "In2.Cu" signal "IN1")
		(8 "In3.Cu" signal "GND1")
		(10 "In4.Cu" signal "IN2")
		(12 "In5.Cu" signal "GND2")
		(14 "In6.Cu" signal "IN3")
		(16 "In7.Cu" signal "GND3")
		(18 "In8.Cu" signal "VCC")
		(20 "In9.Cu" signal "VCC1")
		(22 "In10.Cu" signal "GND4")
		(24 "In11.Cu" signal "IN4")
		(26 "In12.Cu" signal "GND5")
		(28 "In13.Cu" signal "IN5")
		(30 "In14.Cu" signal "GND6")
		(32 "In15.Cu" signal "IN6")
		(34 "In16.Cu" signal "GND7")
		(2 "B.Cu" signal "BOTTOM")
		(9 "F.Adhes" user "F.Adhesive")
		(11 "B.Adhes" user "B.Adhesive")
		(13 "F.Paste" user "Package Geometry/Pastemask Top")
		(15 "B.Paste" user "Package Geometry/Pastemask Bottom")
		(5 "F.SilkS" user "Ref Des/Silkscreen Top")
		(7 "B.SilkS" user "Ref Des/Silkscreen Bottom")
		(1 "F.Mask" user "Board Geometry/Soldermask Top")
		(3 "B.Mask" user "Board Geometry/Soldermask Bottom")
		(17 "Dwgs.User" user "User.Drawings")
		(19 "Cmts.User" user "User.Comments")
		(21 "Eco1.User" user "User.Eco1")
		(23 "Eco2.User" user "User.Eco2")
		(25 "Edge.Cuts" user "Board Geometry/Outline")
		(27 "Margin" user)
		(31 "F.CrtYd" user "Package Geometry/Place Bound Top")
		(29 "B.CrtYd" user "Package Geometry/Place Bound Bottom")
		(35 "F.Fab" user "Ref Des/Assembly Top")
		(33 "B.Fab" user "Ref Des/Assembly Bottom")
	)
	(footprint ""
		(layer "F.Cu")
		(at 211.85378 -4.699)
		(property "Reference" "J73"
			(at -4.18211 1.016 90)
			(unlocked yes)
			(layer "F.SilkS")
			(effects
				(font
					(size 0.7874 0.5842)
					(thickness 0.1524)
				)
				(justify left)
			)
		)
		(property "Value" ""
			(at 0 0 0)
			(layer "F.Fab")
			(effects
				(font
					(size 1.27 1.27)
				)
			)
		)
		(duplicate_pad_numbers_are_jumpers no)
		(fp_line
			(start -1.2192 -2.1082)
			(end 1.2192 -2.1082)
			(stroke
				(width 0.1524)
				(type default)
			)
			(layer "F.SilkS")
		)
		(fp_line
			(start -1.2192 2.1082)
			(end -1.2192 -2.1082)
			(stroke
				(width 0.1524)
				(type default)
			)
			(layer "F.SilkS")
		)
		(fp_line
			(start 1.2192 -2.1082)
			(end 1.2192 2.1082)
			(stroke
				(width 0.1524)
				(type default)
			)
			(layer "F.SilkS")
		)
		(fp_line
			(start 1.2192 2.1082)
			(end -1.2192 2.1082)
			(stroke
				(width 0.1524)
				(type default)
			)
			(layer "F.SilkS")
		)
		(pad "" np_thru_hole circle
			(at -2.8829 -1.27 270)
			(size 1.0414 1.0414)
			(drill 1.0414)
			(layers "*.Cu" "*.Mask")
			(clearance 0.381)
			(thermal_gap 0.381)
		)
		(pad "" np_thru_hole circle
			(at -2.8829 1.27 270)
			(size 1.0414 1.0414)
			(drill 1.0414)
			(layers "*.Cu" "*.Mask")
			(clearance 0.381)
			(thermal_gap 0.381)
		)
		(pad "" np_thru_hole circle
			(at 3.4671 -1.27 270)
			(size 1.0414 1.0414)
			(drill 1.0414)
			(layers "*.Cu" "*.Mask")
			(clearance 0.381)
			(thermal_gap 0.381)
		)
		(pad "" np_thru_hole circle
			(at 3.4671 1.27 270)
			(size 1.0414 1.0414)
			(drill 1.0414)
			(layers "*.Cu" "*.Mask")
			(clearance 0.381)
			(thermal_gap 0.381)
		)
		(pad "1" smd rect
			(at 0.8255 -0.249936 270)
			(size 0.3048 0.508)
			(layers "F.Cu" "F.Mask" "F.Paste")
			(net "DELTA_L_85_5INCH_IN3_DN")
		)
		(pad "2" smd rect
			(at 0.8255 0.249936 270)
			(size 0.3048 0.508)
			(layers "F.Cu" "F.Mask" "F.Paste")
			(net "DELTA_L_85_5INCH_IN3_DP")
		)
		(pad "3" smd circle
			(at 0 0)
			(size 0 0)
			(layers "F.Cu" "F.Mask" "F.Paste")
			(net "DELTA_L_GND_1")
		)
		(zone
			(layer "F.Cu")
			(hatch none 0.5)
			(connect_pads
				(clearance 0)
			)
			(min_thickness 0.25)
			(keepout
				(tracks not_allowed)
				(vias allowed)
				(pads allowed)
				(copperpour not_allowed)
				(footprints allowed)
			)
			(placement
				(enabled no)
				(sheetname "")
			)
			(fill
				(thermal_gap 0.5)
				(thermal_bridge_width 0.5)
				(island_removal_mode 0)
			)
			(polygon
				(pts
					(xy 212.97138 -5.24764) (xy 212.97138 -5.152136) (xy 212.37448 -5.152136) (xy 212.37448 -4.745736)
					(xy 212.97138 -4.745736) (xy 212.97138 -4.652264) (xy 212.37448 -4.652264) (xy 212.37448 -4.245864)
					(xy 212.97138 -4.245864) (xy 212.97138 -4.15036) (xy 212.27288 -4.15036) (xy 212.27288 -5.24764)
				)
			)
		)
		(zone
			(layers "F.Cu" "B.Cu" "In1.Cu" "In2.Cu" "In3.Cu" "In4.Cu" "In5.Cu" "In6.Cu"
				"In7.Cu" "In8.Cu" "In9.Cu" "In10.Cu" "In11.Cu" "In12.Cu" "In13.Cu" "In14.Cu"
				"In15.Cu" "In16.Cu"
			)
			(hatch none 0.5)
			(connect_pads
				(clearance 0)
			)
			(min_thickness 0.25)
			(keepout
				(tracks not_allowed)
				(vias allowed)
				(pads allowed)
				(copperpour not_allowed)
				(footprints allowed)
			)
			(placement
				(enabled no)
				(sheetname "")
			)
			(fill
				(thermal_gap 0.5)
				(thermal_bridge_width 0.5)
				(island_removal_mode 0)
			)
			(polygon
				(pts
					(arc
						(start 209.89798 -5.969)
						(mid 208.04378 -5.969)
						(end 209.89798 -5.969)
					)
				)
			)
		)
		(zone
			(layers "F.Cu" "B.Cu" "In1.Cu" "In2.Cu" "In3.Cu" "In4.Cu" "In5.Cu" "In6.Cu"
				"In7.Cu" "In8.Cu" "In9.Cu" "In10.Cu" "In11.Cu" "In12.Cu" "In13.Cu" "In14.Cu"
				"In15.Cu" "In16.Cu"
			)
			(hatch none 0.5)
			(connect_pads
				(clearance 0)
			)
			(min_thickness 0.25)
			(keepout
				(tracks not_allowed)
				(vias allowed)
				(pads allowed)
				(copperpour not_allowed)
				(footprints allowed)
			)
			(placement
				(enabled no)
				(sheetname "")
			)
			(fill
				(thermal_gap 0.5)
				(thermal_bridge_width 0.5)
				(island_removal_mode 0)
			)
			(polygon
				(pts
					(arc
						(start 209.89798 -3.429)
						(mid 208.04378 -3.429)
						(end 209.89798 -3.429)
					)
				)
			)
		)
		(zone
			(layers "F.Cu" "B.Cu" "In1.Cu" "In2.Cu" "In3.Cu" "In4.Cu" "In5.Cu" "In6.Cu"
				"In7.Cu" "In8.Cu" "In9.Cu" "In10.Cu" "In11.Cu" "In12.Cu" "In13.Cu" "In14.Cu"
				"In15.Cu" "In16.Cu"
			)
			(hatch none 0.5)
			(connect_pads
				(clearance 0)
			)
			(min_thickness 0.25)
			(keepout
				(tracks not_allowed)
				(vias allowed)
				(pads allowed)
				(copperpour not_allowed)
				(footprints allowed)
			)
			(placement
				(enabled no)
				(sheetname "")
			)
			(fill
				(thermal_gap 0.5)
				(thermal_bridge_width 0.5)
				(island_removal_mode 0)
			)
			(polygon
				(pts
					(arc
						(start 216.24798 -5.969)
						(mid 214.39378 -5.969)
						(end 216.24798 -5.969)
					)
				)
			)
		)
		(zone
			(layers "F.Cu" "B.Cu" "In1.Cu" "In2.Cu" "In3.Cu" "In4.Cu" "In5.Cu" "In6.Cu"
				"In7.Cu" "In8.Cu" "In9.Cu" "In10.Cu" "In11.Cu" "In12.Cu" "In13.Cu" "In14.Cu"
				"In15.Cu" "In16.Cu"
			)
			(hatch none 0.5)
			(connect_pads
				(clearance 0)
			)
			(min_thickness 0.25)
			(keepout
				(tracks not_allowed)
				(vias allowed)
				(pads allowed)
				(copperpour not_allowed)
				(footprints allowed)
			)
			(placement
				(enabled no)
				(sheetname "")
			)
			(fill
				(thermal_gap 0.5)
				(thermal_bridge_width 0.5)
				(island_removal_mode 0)
			)
			(polygon
				(pts
					(arc
						(start 216.24798 -3.429)
						(mid 214.39378 -3.429)
						(end 216.24798 -3.429)
					)
				)
			)
		)
	)
)
